(kicad_pcb
	(version 20260206)
	(generator "pcbnew")
	(generator_version "10.0")
	(general
		(thickness 1.6)
		(legacy_teardrops no)
	)
	(paper "A4")
	(title_block
		(title "01162023_DA0F0TEBIF0_F0T_Expander_BD_F_brd_V02_OCP.brd")
		(comment 1 "Grand Teton / footprints 851-857 of 9728")
	)
	(layers
		(0 "F.Cu" signal "TOP")
		(4 "In1.Cu" signal "GND")
		(6 "In2.Cu" signal "VCC")
		(8 "In3.Cu" signal "VCC1")
		(10 "In4.Cu" signal "GND1")
		(12 "In5.Cu" signal "IN1")
		(14 "In6.Cu" signal "GND2")
		(16 "In7.Cu" signal "IN2")
		(18 "In8.Cu" signal "GND3")
		(20 "In9.Cu" signal "IN3")
		(22 "In10.Cu" signal "GND4")
		(24 "In11.Cu" signal "IN4")
		(26 "In12.Cu" signal "GND5")
		(28 "In13.Cu" signal "IN5")
		(30 "In14.Cu" signal "GND6")
		(32 "In15.Cu" signal "IN6")
		(34 "In16.Cu" signal "GND7")
		(2 "B.Cu" signal "BOTTOM")
		(9 "F.Adhes" user "F.Adhesive")
		(11 "B.Adhes" user "B.Adhesive")
		(13 "F.Paste" user "Package Geometry/Pastemask Top")
		(15 "B.Paste" user "Package Geometry/Pastemask Bottom")
		(5 "F.SilkS" user "Ref Des/Silkscreen Top")
		(7 "B.SilkS" user "Ref Des/Silkscreen Bottom")
		(1 "F.Mask" user "Board Geometry/Soldermask Top")
		(3 "B.Mask" user "Board Geometry/Soldermask Bottom")
		(17 "Dwgs.User" user "User.Drawings")
		(19 "Cmts.User" user "User.Comments")
		(21 "Eco1.User" user "User.Eco1")
		(23 "Eco2.User" user "User.Eco2")
		(25 "Edge.Cuts" user "Board Geometry/Outline")
		(27 "Margin" user)
		(31 "F.CrtYd" user "Package Geometry/Place Bound Top")
		(29 "B.CrtYd" user "Package Geometry/Place Bound Bottom")
		(35 "F.Fab" user "Ref Des/Assembly Top")
		(33 "B.Fab" user "Ref Des/Assembly Bottom")
	)
	(footprint ""
		(layer "F.Cu")
		(at 78.02499 -14.735302 180)
		(property "Reference" "C2716"
			(at 0 0 180)
			(layer "F.SilkS")
			(hide yes)
			(effects
				(font
					(size 1.27 1.27)
				)
			)
		)
		(property "Value" ""
			(at 0 0 180)
			(layer "F.Fab")
			(effects
				(font
					(size 1.27 1.27)
				)
			)
		)
		(duplicate_pad_numbers_are_jumpers no)
		(fp_line
			(start 0.7874 0.4064)
			(end -0.7874 0.4064)
			(stroke
				(width 0.1524)
				(type default)
			)
			(layer "F.SilkS")
		)
		(fp_line
			(start 0.7874 -0.4064)
			(end 0.7874 0.4064)
			(stroke
				(width 0.1524)
				(type default)
			)
			(layer "F.SilkS")
		)
		(fp_line
			(start -0.7874 0.4064)
			(end -0.7874 -0.4064)
			(stroke
				(width 0.1524)
				(type default)
			)
			(layer "F.SilkS")
		)
		(fp_line
			(start -0.7874 -0.4064)
			(end 0.7874 -0.4064)
			(stroke
				(width 0.1524)
				(type default)
			)
			(layer "F.SilkS")
		)
		(fp_line
			(start 0.67945 0.3048)
			(end 0.120396 0.3048)
			(stroke
				(width 0.1)
				(type default)
			)
			(layer "F.Fab")
		)
		(fp_line
			(start 0.67945 -0.3048)
			(end 0.67945 0.3048)
			(stroke
				(width 0.1)
				(type default)
			)
			(layer "F.Fab")
		)
		(fp_line
			(start 0.12065 -0.2794)
			(end 0.12065 -0.3048)
			(stroke
				(width 0.1)
				(type default)
			)
			(layer "F.Fab")
		)
		(fp_line
			(start 0.12065 -0.3048)
			(end 0.67945 -0.3048)
			(stroke
				(width 0.1)
				(type default)
			)
			(layer "F.Fab")
		)
		(fp_line
			(start 0.120396 0.3048)
			(end 0.120396 0.2794)
			(stroke
				(width 0.1)
				(type default)
			)
			(layer "F.Fab")
		)
		(fp_line
			(start 0.120396 0.2794)
			(end -0.12065 0.2794)
			(stroke
				(width 0.1)
				(type default)
			)
			(layer "F.Fab")
		)
		(fp_line
			(start -0.12065 0.3048)
			(end -0.67945 0.3048)
			(stroke
				(width 0.1)
				(type default)
			)
			(layer "F.Fab")
		)
		(fp_line
			(start -0.12065 0.2794)
			(end -0.12065 0.3048)
			(stroke
				(width 0.1)
				(type default)
			)
			(layer "F.Fab")
		)
		(fp_line
			(start -0.12065 -0.2794)
			(end 0.12065 -0.2794)
			(stroke
				(width 0.1)
				(type default)
			)
			(layer "F.Fab")
		)
		(fp_line
			(start -0.12065 -0.305054)
			(end -0.12065 -0.2794)
			(stroke
				(width 0.1)
				(type default)
			)
			(layer "F.Fab")
		)
		(fp_line
			(start -0.67945 0.3048)
			(end -0.67945 -0.305054)
			(stroke
				(width 0.1)
				(type default)
			)
			(layer "F.Fab")
		)
		(fp_line
			(start -0.67945 -0.305054)
			(end -0.12065 -0.305054)
			(stroke
				(width 0.1)
				(type default)
			)
			(layer "F.Fab")
		)
		(pad "1" smd circle
			(at -0.40005 0 180)
			(size 0 0)
			(layers "F.Cu" "F.Mask" "F.Paste")
			(net "GND")
		)
		(pad "2" smd circle
			(at 0.40005 0 180)
			(size 0 0)
			(layers "F.Cu" "F.Mask" "F.Paste")
			(net "P3V3_SSD2")
		)
	)
	(footprint ""
		(layer "F.Cu")
		(at 14.668246 -215.320372 180)
		(property "Reference" "R6570"
			(at 0 0 180)
			(layer "F.SilkS")
			(hide yes)
			(effects
				(font
					(size 1.27 1.27)
				)
			)
		)
		(property "Value" ""
			(at 0 0 180)
			(layer "F.Fab")
			(effects
				(font
					(size 1.27 1.27)
				)
			)
		)
		(duplicate_pad_numbers_are_jumpers no)
		(fp_line
			(start 0.7874 0.4064)
			(end -0.7874 0.4064)
			(stroke
				(width 0.1524)
				(type default)
			)
			(layer "F.SilkS")
		)
		(fp_line
			(start 0.7874 -0.4064)
			(end 0.7874 0.4064)
			(stroke
				(width 0.1524)
				(type default)
			)
			(layer "F.SilkS")
		)
		(fp_line
			(start -0.7874 0.4064)
			(end -0.7874 -0.4064)
			(stroke
				(width 0.1524)
				(type default)
			)
			(layer "F.SilkS")
		)
		(fp_line
			(start -0.7874 -0.4064)
			(end 0.7874 -0.4064)
			(stroke
				(width 0.1524)
				(type default)
			)
			(layer "F.SilkS")
		)
		(fp_line
			(start 0.67945 0.3048)
			(end 0.120396 0.3048)
			(stroke
				(width 0.1)
				(type default)
			)
			(layer "F.Fab")
		)
		(fp_line
			(start 0.67945 -0.3048)
			(end 0.67945 0.3048)
			(stroke
				(width 0.1)
				(type default)
			)
			(layer "F.Fab")
		)
		(fp_line
			(start 0.12065 -0.2794)
			(end 0.12065 -0.3048)
			(stroke
				(width 0.1)
				(type default)
			)
			(layer "F.Fab")
		)
		(fp_line
			(start 0.12065 -0.3048)
			(end 0.67945 -0.3048)
			(stroke
				(width 0.1)
				(type default)
			)
			(layer "F.Fab")
		)
		(fp_line
			(start 0.120396 0.3048)
			(end 0.120396 0.2794)
			(stroke
				(width 0.1)
				(type default)
			)
			(layer "F.Fab")
		)
		(fp_line
			(start 0.120396 0.2794)
			(end -0.12065 0.2794)
			(stroke
				(width 0.1)
				(type default)
			)
			(layer "F.Fab")
		)
		(fp_line
			(start -0.12065 0.3048)
			(end -0.67945 0.3048)
			(stroke
				(width 0.1)
				(type default)
			)
			(layer "F.Fab")
		)
		(fp_line
			(start -0.12065 0.2794)
			(end -0.12065 0.3048)
			(stroke
				(width 0.1)
				(type default)
			)
			(layer "F.Fab")
		)
		(fp_line
			(start -0.12065 -0.2794)
			(end 0.12065 -0.2794)
			(stroke
				(width 0.1)
				(type default)
			)
			(layer "F.Fab")
		)
		(fp_line
			(start -0.12065 -0.305054)
			(end -0.12065 -0.2794)
			(stroke
				(width 0.1)
				(type default)
			)
			(layer "F.Fab")
		)
		(fp_line
			(start -0.67945 0.3048)
			(end -0.67945 -0.305054)
			(stroke
				(width 0.1)
				(type default)
			)
			(layer "F.Fab")
		)
		(fp_line
			(start -0.67945 -0.305054)
			(end -0.12065 -0.305054)
			(stroke
				(width 0.1)
				(type default)
			)
			(layer "F.Fab")
		)
		(pad "1" smd circle
			(at -0.40005 0 180)
			(size 0 0)
			(layers "F.Cu" "F.Mask" "F.Paste")
			(net "PWR_EN_PEX_R")
		)
		(pad "2" smd circle
			(at 0.40005 0 180)
			(size 0 0)
			(layers "F.Cu" "F.Mask" "F.Paste")
			(net "PEX0_P1V8_PLL_EN")
		)
	)
	(footprint ""
		(layer "F.Cu")
		(at 454.896982 -116.611654 180)
		(property "Reference" "PR7055"
			(at 0 0 180)
			(layer "F.SilkS")
			(hide yes)
			(effects
				(font
					(size 1.27 1.27)
				)
			)
		)
		(property "Value" ""
			(at 0 0 180)
			(layer "F.Fab")
			(effects
				(font
					(size 1.27 1.27)
				)
			)
		)
		(duplicate_pad_numbers_are_jumpers no)
		(fp_line
			(start 0.7874 0.4064)
			(end -0.7874 0.4064)
			(stroke
				(width 0.1524)
				(type default)
			)
			(layer "F.SilkS")
		)
		(fp_line
			(start 0.7874 -0.4064)
			(end 0.7874 0.4064)
			(stroke
				(width 0.1524)
				(type default)
			)
			(layer "F.SilkS")
		)
		(fp_line
			(start -0.7874 0.4064)
			(end -0.7874 -0.4064)
			(stroke
				(width 0.1524)
				(type default)
			)
			(layer "F.SilkS")
		)
		(fp_line
			(start -0.7874 -0.4064)
			(end 0.7874 -0.4064)
			(stroke
				(width 0.1524)
				(type default)
			)
			(layer "F.SilkS")
		)
		(fp_line
			(start 0.67945 0.3048)
			(end 0.120396 0.3048)
			(stroke
				(width 0.1)
				(type default)
			)
			(layer "F.Fab")
		)
		(fp_line
			(start 0.67945 -0.3048)
			(end 0.67945 0.3048)
			(stroke
				(width 0.1)
				(type default)
			)
			(layer "F.Fab")
		)
		(fp_line
			(start 0.12065 -0.2794)
			(end 0.12065 -0.3048)
			(stroke
				(width 0.1)
				(type default)
			)
			(layer "F.Fab")
		)
		(fp_line
			(start 0.12065 -0.3048)
			(end 0.67945 -0.3048)
			(stroke
				(width 0.1)
				(type default)
			)
			(layer "F.Fab")
		)
		(fp_line
			(start 0.120396 0.3048)
			(end 0.120396 0.2794)
			(stroke
				(width 0.1)
				(type default)
			)
			(layer "F.Fab")
		)
		(fp_line
			(start 0.120396 0.2794)
			(end -0.12065 0.2794)
			(stroke
				(width 0.1)
				(type default)
			)
			(layer "F.Fab")
		)
		(fp_line
			(start -0.12065 0.3048)
			(end -0.67945 0.3048)
			(stroke
				(width 0.1)
				(type default)
			)
			(layer "F.Fab")
		)
		(fp_line
			(start -0.12065 0.2794)
			(end -0.12065 0.3048)
			(stroke
				(width 0.1)
				(type default)
			)
			(layer "F.Fab")
		)
		(fp_line
			(start -0.12065 -0.2794)
			(end 0.12065 -0.2794)
			(stroke
				(width 0.1)
				(type default)
			)
			(layer "F.Fab")
		)
		(fp_line
			(start -0.12065 -0.305054)
			(end -0.12065 -0.2794)
			(stroke
				(width 0.1)
				(type default)
			)
			(layer "F.Fab")
		)
		(fp_line
			(start -0.67945 0.3048)
			(end -0.67945 -0.305054)
			(stroke
				(width 0.1)
				(type default)
			)
			(layer "F.Fab")
		)
		(fp_line
			(start -0.67945 -0.305054)
			(end -0.12065 -0.305054)
			(stroke
				(width 0.1)
				(type default)
			)
			(layer "F.Fab")
		)
		(pad "1" smd circle
			(at -0.40005 0 180)
			(size 0 0)
			(layers "F.Cu" "F.Mask" "F.Paste")
			(net "P12V_NIC7_CO_OV_FB")
		)
		(pad "2" smd circle
			(at 0.40005 0 180)
			(size 0 0)
			(layers "F.Cu" "F.Mask" "F.Paste")
			(net "P12V_AUX")
		)
	)
	(footprint ""
		(layer "F.Cu")
		(at 114.800888 -163.217352)
		(property "Reference" "R4430"
			(at 0 0 0)
			(layer "F.SilkS")
			(hide yes)
			(effects
				(font
					(size 1.27 1.27)
				)
			)
		)
		(property "Value" ""
			(at 0 0 0)
			(layer "F.Fab")
			(effects
				(font
					(size 1.27 1.27)
				)
			)
		)
		(duplicate_pad_numbers_are_jumpers no)
		(fp_line
			(start -0.7874 -0.4064)
			(end 0.7874 -0.4064)
			(stroke
				(width 0.1524)
				(type default)
			)
			(layer "F.SilkS")
		)
		(fp_line
			(start -0.7874 0.4064)
			(end -0.7874 -0.4064)
			(stroke
				(width 0.1524)
				(type default)
			)
			(layer "F.SilkS")
		)
		(fp_line
			(start 0.7874 -0.4064)
			(end 0.7874 0.4064)
			(stroke
				(width 0.1524)
				(type default)
			)
			(layer "F.SilkS")
		)
		(fp_line
			(start 0.7874 0.4064)
			(end -0.7874 0.4064)
			(stroke
				(width 0.1524)
				(type default)
			)
			(layer "F.SilkS")
		)
		(fp_line
			(start -0.67945 -0.305054)
			(end -0.12065 -0.305054)
			(stroke
				(width 0.1)
				(type default)
			)
			(layer "F.Fab")
		)
		(fp_line
			(start -0.67945 0.3048)
			(end -0.67945 -0.305054)
			(stroke
				(width 0.1)
				(type default)
			)
			(layer "F.Fab")
		)
		(fp_line
			(start -0.12065 -0.305054)
			(end -0.12065 -0.2794)
			(stroke
				(width 0.1)
				(type default)
			)
			(layer "F.Fab")
		)
		(fp_line
			(start -0.12065 -0.2794)
			(end 0.12065 -0.2794)
			(stroke
				(width 0.1)
				(type default)
			)
			(layer "F.Fab")
		)
		(fp_line
			(start -0.12065 0.2794)
			(end -0.12065 0.3048)
			(stroke
				(width 0.1)
				(type default)
			)
			(layer "F.Fab")
		)
		(fp_line
			(start -0.12065 0.3048)
			(end -0.67945 0.3048)
			(stroke
				(width 0.1)
				(type default)
			)
			(layer "F.Fab")
		)
		(fp_line
			(start 0.120396 0.2794)
			(end -0.12065 0.2794)
			(stroke
				(width 0.1)
				(type default)
			)
			(layer "F.Fab")
		)
		(fp_line
			(start 0.120396 0.3048)
			(end 0.120396 0.2794)
			(stroke
				(width 0.1)
				(type default)
			)
			(layer "F.Fab")
		)
		(fp_line
			(start 0.12065 -0.3048)
			(end 0.67945 -0.3048)
			(stroke
				(width 0.1)
				(type default)
			)
			(layer "F.Fab")
		)
		(fp_line
			(start 0.12065 -0.2794)
			(end 0.12065 -0.3048)
			(stroke
				(width 0.1)
				(type default)
			)
			(layer "F.Fab")
		)
		(fp_line
			(start 0.67945 -0.3048)
			(end 0.67945 0.3048)
			(stroke
				(width 0.1)
				(type default)
			)
			(layer "F.Fab")
		)
		(fp_line
			(start 0.67945 0.3048)
			(end 0.120396 0.3048)
			(stroke
				(width 0.1)
				(type default)
			)
			(layer "F.Fab")
		)
		(pad "1" smd circle
			(at -0.40005 0)
			(size 0 0)
			(layers "F.Cu" "F.Mask" "F.Paste")
			(net "PWRGD_P3V3_AUX")
		)
		(pad "2" smd circle
			(at 0.40005 0)
			(size 0 0)
			(layers "F.Cu" "F.Mask" "F.Paste")
			(net "PWRGD_P3V3_AUX_R")
		)
	)
	(footprint ""
		(layer "F.Cu")
		(at 175.871886 -24.807418)
		(property "Reference" "R429"
			(at 0 0 0)
			(layer "F.SilkS")
			(hide yes)
			(effects
				(font
					(size 1.27 1.27)
				)
			)
		)
		(property "Value" ""
			(at 0 0 0)
			(layer "F.Fab")
			(effects
				(font
					(size 1.27 1.27)
				)
			)
		)
		(duplicate_pad_numbers_are_jumpers no)
		(fp_line
			(start -0.7874 -0.4064)
			(end 0.7874 -0.4064)
			(stroke
				(width 0.1524)
				(type default)
			)
			(layer "F.SilkS")
		)
		(fp_line
			(start -0.7874 0.4064)
			(end -0.7874 -0.4064)
			(stroke
				(width 0.1524)
				(type default)
			)
			(layer "F.SilkS")
		)
		(fp_line
			(start 0.7874 -0.4064)
			(end 0.7874 0.4064)
			(stroke
				(width 0.1524)
				(type default)
			)
			(layer "F.SilkS")
		)
		(fp_line
			(start 0.7874 0.4064)
			(end -0.7874 0.4064)
			(stroke
				(width 0.1524)
				(type default)
			)
			(layer "F.SilkS")
		)
		(fp_line
			(start -0.67945 -0.305054)
			(end -0.12065 -0.305054)
			(stroke
				(width 0.1)
				(type default)
			)
			(layer "F.Fab")
		)
		(fp_line
			(start -0.67945 0.3048)
			(end -0.67945 -0.305054)
			(stroke
				(width 0.1)
				(type default)
			)
			(layer "F.Fab")
		)
		(fp_line
			(start -0.12065 -0.305054)
			(end -0.12065 -0.2794)
			(stroke
				(width 0.1)
				(type default)
			)
			(layer "F.Fab")
		)
		(fp_line
			(start -0.12065 -0.2794)
			(end 0.12065 -0.2794)
			(stroke
				(width 0.1)
				(type default)
			)
			(layer "F.Fab")
		)
		(fp_line
			(start -0.12065 0.2794)
			(end -0.12065 0.3048)
			(stroke
				(width 0.1)
				(type default)
			)
			(layer "F.Fab")
		)
		(fp_line
			(start -0.12065 0.3048)
			(end -0.67945 0.3048)
			(stroke
				(width 0.1)
				(type default)
			)
			(layer "F.Fab")
		)
		(fp_line
			(start 0.120396 0.2794)
			(end -0.12065 0.2794)
			(stroke
				(width 0.1)
				(type default)
			)
			(layer "F.Fab")
		)
		(fp_line
			(start 0.120396 0.3048)
			(end 0.120396 0.2794)
			(stroke
				(width 0.1)
				(type default)
			)
			(layer "F.Fab")
		)
		(fp_line
			(start 0.12065 -0.3048)
			(end 0.67945 -0.3048)
			(stroke
				(width 0.1)
				(type default)
			)
			(layer "F.Fab")
		)
		(fp_line
			(start 0.12065 -0.2794)
			(end 0.12065 -0.3048)
			(stroke
				(width 0.1)
				(type default)
			)
			(layer "F.Fab")
		)
		(fp_line
			(start 0.67945 -0.3048)
			(end 0.67945 0.3048)
			(stroke
				(width 0.1)
				(type default)
			)
			(layer "F.Fab")
		)
		(fp_line
			(start 0.67945 0.3048)
			(end 0.120396 0.3048)
			(stroke
				(width 0.1)
				(type default)
			)
			(layer "F.Fab")
		)
		(pad "1" smd circle
			(at -0.40005 0)
			(size 0 0)
			(layers "F.Cu" "F.Mask" "F.Paste")
			(net "P3V3_SSD6")
		)
		(pad "2" smd circle
			(at 0.40005 0)
			(size 0 0)
			(layers "F.Cu" "F.Mask" "F.Paste")
			(net "PU_CLKREQ6")
		)
	)
	(footprint ""
		(layer "F.Cu")
		(at 26.439368 -343.952322 90)
		(property "Reference" "C2157"
			(at 0 0 90)
			(layer "F.SilkS")
			(hide yes)
			(effects
				(font
					(size 1.27 1.27)
				)
			)
		)
		(property "Value" ""
			(at 0 0 90)
			(layer "F.Fab")
			(effects
				(font
					(size 1.27 1.27)
				)
			)
		)
		(duplicate_pad_numbers_are_jumpers no)
		(fp_line
			(start 0.299974 -0.150114)
			(end 0.299974 0.150114)
			(stroke
				(width 0.1)
				(type default)
			)
			(layer "F.Fab")
		)
		(fp_line
			(start -0.299974 -0.150114)
			(end 0.299974 -0.150114)
			(stroke
				(width 0.1)
				(type default)
			)
			(layer "F.Fab")
		)
		(fp_line
			(start 0.299974 0.150114)
			(end -0.299974 0.150114)
			(stroke
				(width 0.1)
				(type default)
			)
			(layer "F.Fab")
		)
		(fp_line
			(start -0.299974 0.150114)
			(end -0.299974 -0.150114)
			(stroke
				(width 0.1)
				(type default)
			)
			(layer "F.Fab")
		)
		(pad "1" smd rect
			(at -0.2667 0 90)
			(size 0.3048 0.381)
			(layers "F.Cu" "F.Mask" "F.Paste")
			(net "P5E_PEX0_STN4_TX_DN<77>")
		)
		(pad "2" smd rect
			(at 0.2667 0 90)
			(size 0.3048 0.381)
			(layers "F.Cu" "F.Mask" "F.Paste")
			(net "P5E_PEX0_STN4_TX_C_DN<77>")
		)
	)
	(footprint ""
		(layer "F.Cu")
		(at 385.354068 -147.969224 90)
		(property "Reference" "C936"
			(at 0 0 90)
			(layer "F.SilkS")
			(hide yes)
			(effects
				(font
					(size 1.27 1.27)
				)
			)
		)
		(property "Value" ""
			(at 0 0 90)
			(layer "F.Fab")
			(effects
				(font
					(size 1.27 1.27)
				)
			)
		)
		(duplicate_pad_numbers_are_jumpers no)
		(fp_line
			(start 1.524 -0.762)
			(end 1.524 0.762)
			(stroke
				(width 0.1524)
				(type default)
			)
			(layer "F.SilkS")
		)
		(fp_line
			(start -1.524 -0.762)
			(end 1.524 -0.762)
			(stroke
				(width 0.1524)
				(type default)
			)
			(layer "F.SilkS")
		)
		(fp_line
			(start 1.524 0.762)
			(end -1.524 0.762)
			(stroke
				(width 0.1524)
				(type default)
			)
			(layer "F.SilkS")
		)
		(fp_line
			(start -1.524 0.762)
			(end -1.524 -0.762)
			(stroke
				(width 0.1524)
				(type default)
			)
			(layer "F.SilkS")
		)
		(fp_line
			(start 1.1049 -0.724916)
			(end -1.1049 -0.724916)
			(stroke
				(width 0.1)
				(type default)
			)
			(layer "F.Fab")
		)
		(fp_line
			(start -1.1049 -0.724916)
			(end -1.1049 0.724916)
			(stroke
				(width 0.1)
				(type default)
			)
			(layer "F.Fab")
		)
		(fp_line
			(start 1.1049 0.724916)
			(end 1.1049 -0.724916)
			(stroke
				(width 0.1)
				(type default)
			)
			(layer "F.Fab")
		)
		(fp_line
			(start -1.1049 0.724916)
			(end 1.1049 0.724916)
			(stroke
				(width 0.1)
				(type default)
			)
			(layer "F.Fab")
		)
		(pad "1" smd rect
			(at -0.889 0 270)
			(size 1.016 1.27)
			(layers "F.Cu" "F.Mask" "F.Paste")
			(net "P12V_NIC6")
		)
		(pad "2" smd rect
			(at 0.889 0 270)
			(size 1.016 1.27)
			(layers "F.Cu" "F.Mask" "F.Paste")
			(net "GND")
		)
	)
)
